(kicad_pcb
	(version 20260206)
	(generator "pcbnew")
	(generator_version "10.0")
	(general
		(thickness 1.6)
		(legacy_teardrops no)
	)
	(paper "A4")
	(title_block
		(title "01162023_DA0F0TEBIF0_F0T_Expander_BD_F_brd_V02_OCP.brd")
		(comment 1 "Grand Teton / footprints 2459-2464 of 9728")
	)
	(layers
		(0 "F.Cu" signal "TOP")
		(4 "In1.Cu" signal "GND")
		(6 "In2.Cu" signal "VCC")
		(8 "In3.Cu" signal "VCC1")
		(10 "In4.Cu" signal "GND1")
		(12 "In5.Cu" signal "IN1")
		(14 "In6.Cu" signal "GND2")
		(16 "In7.Cu" signal "IN2")
		(18 "In8.Cu" signal "GND3")
		(20 "In9.Cu" signal "IN3")
		(22 "In10.Cu" signal "GND4")
		(24 "In11.Cu" signal "IN4")
		(26 "In12.Cu" signal "GND5")
		(28 "In13.Cu" signal "IN5")
		(30 "In14.Cu" signal "GND6")
		(32 "In15.Cu" signal "IN6")
		(34 "In16.Cu" signal "GND7")
		(2 "B.Cu" signal "BOTTOM")
		(9 "F.Adhes" user "F.Adhesive")
		(11 "B.Adhes" user "B.Adhesive")
		(13 "F.Paste" user "Package Geometry/Pastemask Top")
		(15 "B.Paste" user "Package Geometry/Pastemask Bottom")
		(5 "F.SilkS" user "Ref Des/Silkscreen Top")
		(7 "B.SilkS" user "Ref Des/Silkscreen Bottom")
		(1 "F.Mask" user "Board Geometry/Soldermask Top")
		(3 "B.Mask" user "Board Geometry/Soldermask Bottom")
		(17 "Dwgs.User" user "User.Drawings")
		(19 "Cmts.User" user "User.Comments")
		(21 "Eco1.User" user "User.Eco1")
		(23 "Eco2.User" user "User.Eco2")
		(25 "Edge.Cuts" user "Board Geometry/Outline")
		(27 "Margin" user)
		(31 "F.CrtYd" user "Package Geometry/Place Bound Top")
		(29 "B.CrtYd" user "Package Geometry/Place Bound Bottom")
		(35 "F.Fab" user "Ref Des/Assembly Top")
		(33 "B.Fab" user "Ref Des/Assembly Bottom")
	)
	(footprint ""
		(layer "F.Cu")
		(at 366.968786 -149.313392 -90)
		(property "Reference" "U85"
			(at -0.089408 -2.500884 90)
			(unlocked yes)
			(layer "F.SilkS")
			(effects
				(font
					(size 0.7874 0.5842)
					(thickness 0.1524)
				)
			)
		)
		(property "Value" ""
			(at 0 0 270)
			(layer "F.Fab")
			(effects
				(font
					(size 1.27 1.27)
				)
			)
		)
		(duplicate_pad_numbers_are_jumpers no)
		(fp_line
			(start -1.500124 1.500124)
			(end -1.500124 1.004062)
			(stroke
				(width 0.1524)
				(type default)
			)
			(layer "F.SilkS")
		)
		(fp_line
			(start -1.004062 1.500124)
			(end -1.500124 1.500124)
			(stroke
				(width 0.1524)
				(type default)
			)
			(layer "F.SilkS")
		)
		(fp_line
			(start 1.500124 1.500124)
			(end 1.004062 1.500124)
			(stroke
				(width 0.1524)
				(type default)
			)
			(layer "F.SilkS")
		)
		(fp_line
			(start 1.500124 1.004062)
			(end 1.500124 1.500124)
			(stroke
				(width 0.1524)
				(type default)
			)
			(layer "F.SilkS")
		)
		(fp_line
			(start -1.500124 -1.004062)
			(end -1.500124 -1.500124)
			(stroke
				(width 0.1524)
				(type default)
			)
			(layer "F.SilkS")
		)
		(fp_line
			(start -1.500124 -1.500124)
			(end -1.004062 -1.500124)
			(stroke
				(width 0.1524)
				(type default)
			)
			(layer "F.SilkS")
		)
		(fp_line
			(start 1.004062 -1.500124)
			(end 1.500124 -1.500124)
			(stroke
				(width 0.1524)
				(type default)
			)
			(layer "F.SilkS")
		)
		(fp_line
			(start 1.500124 -1.500124)
			(end 1.500124 -1.004062)
			(stroke
				(width 0.1524)
				(type default)
			)
			(layer "F.SilkS")
		)
		(fp_poly
			(pts
				(xy -1.93421 -2.102612) (xy -2.652522 -1.3843) (xy -1.575054 -1.025144)
			)
			(stroke
				(width 0)
				(type default)
			)
			(fill yes)
			(layer "F.SilkS")
		)
		(fp_line
			(start -1.500124 1.500124)
			(end -1.500124 -1.500124)
			(stroke
				(width 0.1)
				(type default)
			)
			(layer "F.Fab")
		)
		(fp_line
			(start 1.500124 1.500124)
			(end -1.500124 1.500124)
			(stroke
				(width 0.1)
				(type default)
			)
			(layer "F.Fab")
		)
		(fp_line
			(start -1.500124 -1.500124)
			(end 1.500124 -1.500124)
			(stroke
				(width 0.1)
				(type default)
			)
			(layer "F.Fab")
		)
		(fp_line
			(start 1.500124 -1.500124)
			(end 1.500124 1.500124)
			(stroke
				(width 0.1)
				(type default)
			)
			(layer "F.Fab")
		)
		(fp_poly
			(pts
				(xy -2.847848 -1.258062) (xy -2.847848 -0.242062) (xy -1.831848 -0.750062)
			)
			(stroke
				(width 0)
				(type default)
			)
			(fill yes)
			(layer "F.Fab")
		)
		(pad "1" smd rect
			(at -1.400048 -0.750062 180)
			(size 0.2286 0.6096)
			(layers "F.Cu" "F.Mask" "F.Paste")
			(net "NIC6_ADC_A1")
		)
		(pad "2" smd rect
			(at -1.400048 -0.249936 180)
			(size 0.2286 0.6096)
			(layers "F.Cu" "F.Mask" "F.Paste")
			(net "NIC6_ADC_A0")
		)
		(pad "3" smd rect
			(at -1.400048 0.249936 180)
			(size 0.2286 0.6096)
			(layers "F.Cu" "F.Mask" "F.Paste")
			(net "NIC6_ADC_ALERT_N")
		)
		(pad "4" smd rect
			(at -1.400048 0.750062 180)
			(size 0.2286 0.6096)
			(layers "F.Cu" "F.Mask" "F.Paste")
			(net "SMB_NIC6_ADC_SDA")
		)
		(pad "5" smd rect
			(at -0.750062 1.400048 270)
			(size 0.2286 0.6096)
			(layers "F.Cu" "F.Mask" "F.Paste")
			(net "SMB_NIC6_ADC_SCL")
		)
		(pad "6" smd rect
			(at -0.249936 1.400048 270)
			(size 0.2286 0.6096)
			(layers "F.Cu" "F.Mask" "F.Paste")
			(net "Net_8630")
		)
		(pad "7" smd rect
			(at 0.249936 1.400048 270)
			(size 0.2286 0.6096)
			(layers "F.Cu" "F.Mask" "F.Paste")
			(net "Net_8629")
		)
		(pad "8" smd rect
			(at 0.750062 1.400048 270)
			(size 0.2286 0.6096)
			(layers "F.Cu" "F.Mask" "F.Paste")
			(net "Net_8628")
		)
		(pad "9" smd rect
			(at 1.400048 0.750062 180)
			(size 0.2286 0.6096)
			(layers "F.Cu" "F.Mask" "F.Paste")
			(net "P3V3_AUX")
		)
		(pad "10" smd rect
			(at 1.400048 0.249936 180)
			(size 0.2286 0.6096)
			(layers "F.Cu" "F.Mask" "F.Paste")
			(net "GND")
		)
		(pad "11" smd rect
			(at 1.400048 -0.249936 180)
			(size 0.2286 0.6096)
			(layers "F.Cu" "F.Mask" "F.Paste")
			(net "P12V_NIC6_R")
		)
		(pad "12" smd rect
			(at 1.400048 -0.750062 180)
			(size 0.2286 0.6096)
			(layers "F.Cu" "F.Mask" "F.Paste")
			(net "P12V_NIC6_VIN_N")
		)
		(pad "13" smd rect
			(at 0.750062 -1.400048 270)
			(size 0.2286 0.6096)
			(layers "F.Cu" "F.Mask" "F.Paste")
			(net "P12V_NIC6_VIN_P")
		)
		(pad "14" smd rect
			(at 0.249936 -1.400048 270)
			(size 0.2286 0.6096)
			(layers "F.Cu" "F.Mask" "F.Paste")
			(net "Net_8627")
		)
		(pad "15" smd rect
			(at -0.249936 -1.400048 270)
			(size 0.2286 0.6096)
			(layers "F.Cu" "F.Mask" "F.Paste")
			(net "Net_8626")
		)
		(pad "16" smd rect
			(at -0.750062 -1.400048 270)
			(size 0.2286 0.6096)
			(layers "F.Cu" "F.Mask" "F.Paste")
			(net "Net_8625")
		)
		(pad "TH" smd rect
			(at 0 0 270)
			(size 1.7018 1.7018)
			(layers "F.Cu" "F.Mask" "F.Paste")
			(net "GND")
		)
		(zone
			(layer "F.Cu")
			(hatch none 0.5)
			(connect_pads
				(clearance 0)
			)
			(min_thickness 0.25)
			(keepout
				(tracks not_allowed)
				(vias allowed)
				(pads allowed)
				(copperpour not_allowed)
				(footprints allowed)
			)
			(placement
				(enabled no)
				(sheetname "")
			)
			(fill
				(thermal_gap 0.5)
				(thermal_bridge_width 0.5)
				(island_removal_mode 0)
			)
			(polygon
				(pts
					(xy 366.994186 -150.35784) (xy 368.013234 -150.35784) (xy 368.013234 -148.268944) (xy 365.924338 -148.268944)
					(xy 365.924338 -150.35784) (xy 366.968786 -150.35784) (xy 366.968786 -150.215092) (xy 366.067086 -150.215092)
					(xy 366.067086 -148.411692) (xy 367.870486 -148.411692) (xy 367.870486 -150.215092) (xy 366.994186 -150.215092)
				)
			)
		)
	)
	(footprint ""
		(layer "F.Cu")
		(at 237.047786 -40.037258 90)
		(property "Reference" "U371"
			(at 0.247142 2.373884 90)
			(unlocked yes)
			(layer "F.SilkS")
			(effects
				(font
					(size 0.7874 0.5842)
					(thickness 0.1524)
				)
			)
		)
		(property "Value" ""
			(at 0 0 90)
			(layer "F.Fab")
			(effects
				(font
					(size 1.27 1.27)
				)
			)
		)
		(duplicate_pad_numbers_are_jumpers no)
		(fp_line
			(start -1.949958 -1.610106)
			(end 1.949958 -1.610106)
			(stroke
				(width 0.1524)
				(type default)
			)
			(layer "F.SilkS")
		)
		(fp_line
			(start 1.949958 -1.560068)
			(end 1.949958 1.610106)
			(stroke
				(width 0.1524)
				(type default)
			)
			(layer "F.SilkS")
		)
		(fp_line
			(start 1.949958 1.610106)
			(end -1.949958 1.610106)
			(stroke
				(width 0.1524)
				(type default)
			)
			(layer "F.SilkS")
		)
		(fp_line
			(start -1.949958 1.610106)
			(end -1.949958 -1.610106)
			(stroke
				(width 0.1524)
				(type default)
			)
			(layer "F.SilkS")
		)
		(fp_line
			(start 0.750062 -1.560068)
			(end 0.750062 1.560068)
			(stroke
				(width 0.1)
				(type default)
			)
			(layer "F.Fab")
		)
		(fp_line
			(start -0.750062 -1.560068)
			(end 0.750062 -1.560068)
			(stroke
				(width 0.1)
				(type default)
			)
			(layer "F.Fab")
		)
		(fp_line
			(start 0.750062 1.560068)
			(end -0.750062 1.560068)
			(stroke
				(width 0.1)
				(type default)
			)
			(layer "F.Fab")
		)
		(fp_line
			(start -0.750062 1.560068)
			(end -0.750062 -1.560068)
			(stroke
				(width 0.1)
				(type default)
			)
			(layer "F.Fab")
		)
		(pad "D" smd rect
			(at 1.100074 0)
			(size 1.016 1.4224)
			(layers "F.Cu" "F.Mask" "F.Paste")
			(net "SSD8_AUX_P3V3_EN")
		)
		(pad "G" smd rect
			(at -1.100074 -0.94996)
			(size 1.016 1.4224)
			(layers "F.Cu" "F.Mask" "F.Paste")
			(net "PRSNT_SSD8_R1_N")
		)
		(pad "S" smd rect
			(at -1.100074 0.94996)
			(size 1.016 1.4224)
			(layers "F.Cu" "F.Mask" "F.Paste")
			(net "GND")
		)
	)
	(footprint ""
		(layer "F.Cu")
		(at 76.891642 -350.098614 90)
		(property "Reference" "C143"
			(at 0 0 90)
			(layer "F.SilkS")
			(hide yes)
			(effects
				(font
					(size 1.27 1.27)
				)
			)
		)
		(property "Value" ""
			(at 0 0 90)
			(layer "F.Fab")
			(effects
				(font
					(size 1.27 1.27)
				)
			)
		)
		(duplicate_pad_numbers_are_jumpers no)
		(fp_line
			(start 0.299974 -0.150114)
			(end 0.299974 0.150114)
			(stroke
				(width 0.1)
				(type default)
			)
			(layer "F.Fab")
		)
		(fp_line
			(start -0.299974 -0.150114)
			(end 0.299974 -0.150114)
			(stroke
				(width 0.1)
				(type default)
			)
			(layer "F.Fab")
		)
		(fp_line
			(start 0.299974 0.150114)
			(end -0.299974 0.150114)
			(stroke
				(width 0.1)
				(type default)
			)
			(layer "F.Fab")
		)
		(fp_line
			(start -0.299974 0.150114)
			(end -0.299974 -0.150114)
			(stroke
				(width 0.1)
				(type default)
			)
			(layer "F.Fab")
		)
		(pad "1" smd rect
			(at -0.2667 0 90)
			(size 0.3048 0.381)
			(layers "F.Cu" "F.Mask" "F.Paste")
			(net "P5E_PEX0_STN6_TX_DP<104>")
		)
		(pad "2" smd rect
			(at 0.2667 0 90)
			(size 0.3048 0.381)
			(layers "F.Cu" "F.Mask" "F.Paste")
			(net "P5E_PEX0_STN6_TX_C_DP<104>")
		)
	)
	(footprint ""
		(layer "F.Cu")
		(at 386.899912 -152.295352 180)
		(property "Reference" "R323"
			(at 0 0 180)
			(layer "F.SilkS")
			(hide yes)
			(effects
				(font
					(size 1.27 1.27)
				)
			)
		)
		(property "Value" ""
			(at 0 0 180)
			(layer "F.Fab")
			(effects
				(font
					(size 1.27 1.27)
				)
			)
		)
		(duplicate_pad_numbers_are_jumpers no)
		(fp_line
			(start 0.7874 0.4064)
			(end -0.7874 0.4064)
			(stroke
				(width 0.1524)
				(type default)
			)
			(layer "F.SilkS")
		)
		(fp_line
			(start 0.7874 -0.4064)
			(end 0.7874 0.4064)
			(stroke
				(width 0.1524)
				(type default)
			)
			(layer "F.SilkS")
		)
		(fp_line
			(start -0.7874 0.4064)
			(end -0.7874 -0.4064)
			(stroke
				(width 0.1524)
				(type default)
			)
			(layer "F.SilkS")
		)
		(fp_line
			(start -0.7874 -0.4064)
			(end 0.7874 -0.4064)
			(stroke
				(width 0.1524)
				(type default)
			)
			(layer "F.SilkS")
		)
		(fp_line
			(start 0.67945 0.3048)
			(end 0.120396 0.3048)
			(stroke
				(width 0.1)
				(type default)
			)
			(layer "F.Fab")
		)
		(fp_line
			(start 0.67945 -0.3048)
			(end 0.67945 0.3048)
			(stroke
				(width 0.1)
				(type default)
			)
			(layer "F.Fab")
		)
		(fp_line
			(start 0.12065 -0.2794)
			(end 0.12065 -0.3048)
			(stroke
				(width 0.1)
				(type default)
			)
			(layer "F.Fab")
		)
		(fp_line
			(start 0.12065 -0.3048)
			(end 0.67945 -0.3048)
			(stroke
				(width 0.1)
				(type default)
			)
			(layer "F.Fab")
		)
		(fp_line
			(start 0.120396 0.3048)
			(end 0.120396 0.2794)
			(stroke
				(width 0.1)
				(type default)
			)
			(layer "F.Fab")
		)
		(fp_line
			(start 0.120396 0.2794)
			(end -0.12065 0.2794)
			(stroke
				(width 0.1)
				(type default)
			)
			(layer "F.Fab")
		)
		(fp_line
			(start -0.12065 0.3048)
			(end -0.67945 0.3048)
			(stroke
				(width 0.1)
				(type default)
			)
			(layer "F.Fab")
		)
		(fp_line
			(start -0.12065 0.2794)
			(end -0.12065 0.3048)
			(stroke
				(width 0.1)
				(type default)
			)
			(layer "F.Fab")
		)
		(fp_line
			(start -0.12065 -0.2794)
			(end 0.12065 -0.2794)
			(stroke
				(width 0.1)
				(type default)
			)
			(layer "F.Fab")
		)
		(fp_line
			(start -0.12065 -0.305054)
			(end -0.12065 -0.2794)
			(stroke
				(width 0.1)
				(type default)
			)
			(layer "F.Fab")
		)
		(fp_line
			(start -0.67945 0.3048)
			(end -0.67945 -0.305054)
			(stroke
				(width 0.1)
				(type default)
			)
			(layer "F.Fab")
		)
		(fp_line
			(start -0.67945 -0.305054)
			(end -0.12065 -0.305054)
			(stroke
				(width 0.1)
				(type default)
			)
			(layer "F.Fab")
		)
		(pad "1" smd circle
			(at -0.40005 0 180)
			(size 0 0)
			(layers "F.Cu" "F.Mask" "F.Paste")
			(net "NCSI_NIC6_RXD1")
		)
		(pad "2" smd circle
			(at 0.40005 0 180)
			(size 0 0)
			(layers "F.Cu" "F.Mask" "F.Paste")
			(net "GND")
		)
	)
	(footprint ""
		(layer "F.Cu")
		(at 138.985244 -90.099642 180)
		(property "Reference" "R1564"
			(at 0 0 180)
			(layer "F.SilkS")
			(hide yes)
			(effects
				(font
					(size 1.27 1.27)
				)
			)
		)
		(property "Value" ""
			(at 0 0 180)
			(layer "F.Fab")
			(effects
				(font
					(size 1.27 1.27)
				)
			)
		)
		(duplicate_pad_numbers_are_jumpers no)
		(fp_line
			(start 0.7874 0.4064)
			(end -0.7874 0.4064)
			(stroke
				(width 0.1524)
				(type default)
			)
			(layer "F.SilkS")
		)
		(fp_line
			(start 0.7874 -0.4064)
			(end 0.7874 0.4064)
			(stroke
				(width 0.1524)
				(type default)
			)
			(layer "F.SilkS")
		)
		(fp_line
			(start -0.7874 0.4064)
			(end -0.7874 -0.4064)
			(stroke
				(width 0.1524)
				(type default)
			)
			(layer "F.SilkS")
		)
		(fp_line
			(start -0.7874 -0.4064)
			(end 0.7874 -0.4064)
			(stroke
				(width 0.1524)
				(type default)
			)
			(layer "F.SilkS")
		)
		(fp_line
			(start 0.67945 0.3048)
			(end 0.120396 0.3048)
			(stroke
				(width 0.1)
				(type default)
			)
			(layer "F.Fab")
		)
		(fp_line
			(start 0.67945 -0.3048)
			(end 0.67945 0.3048)
			(stroke
				(width 0.1)
				(type default)
			)
			(layer "F.Fab")
		)
		(fp_line
			(start 0.12065 -0.2794)
			(end 0.12065 -0.3048)
			(stroke
				(width 0.1)
				(type default)
			)
			(layer "F.Fab")
		)
		(fp_line
			(start 0.12065 -0.3048)
			(end 0.67945 -0.3048)
			(stroke
				(width 0.1)
				(type default)
			)
			(layer "F.Fab")
		)
		(fp_line
			(start 0.120396 0.3048)
			(end 0.120396 0.2794)
			(stroke
				(width 0.1)
				(type default)
			)
			(layer "F.Fab")
		)
		(fp_line
			(start 0.120396 0.2794)
			(end -0.12065 0.2794)
			(stroke
				(width 0.1)
				(type default)
			)
			(layer "F.Fab")
		)
		(fp_line
			(start -0.12065 0.3048)
			(end -0.67945 0.3048)
			(stroke
				(width 0.1)
				(type default)
			)
			(layer "F.Fab")
		)
		(fp_line
			(start -0.12065 0.2794)
			(end -0.12065 0.3048)
			(stroke
				(width 0.1)
				(type default)
			)
			(layer "F.Fab")
		)
		(fp_line
			(start -0.12065 -0.2794)
			(end 0.12065 -0.2794)
			(stroke
				(width 0.1)
				(type default)
			)
			(layer "F.Fab")
		)
		(fp_line
			(start -0.12065 -0.305054)
			(end -0.12065 -0.2794)
			(stroke
				(width 0.1)
				(type default)
			)
			(layer "F.Fab")
		)
		(fp_line
			(start -0.67945 0.3048)
			(end -0.67945 -0.305054)
			(stroke
				(width 0.1)
				(type default)
			)
			(layer "F.Fab")
		)
		(fp_line
			(start -0.67945 -0.305054)
			(end -0.12065 -0.305054)
			(stroke
				(width 0.1)
				(type default)
			)
			(layer "F.Fab")
		)
		(pad "1" smd circle
			(at -0.40005 0 180)
			(size 0 0)
			(layers "F.Cu" "F.Mask" "F.Paste")
			(net "P3V3_AUX")
		)
		(pad "2" smd circle
			(at 0.40005 0 180)
			(size 0 0)
			(layers "F.Cu" "F.Mask" "F.Paste")
			(net "SMB_BIC_I2C9_MUX0_SSD5_R_SDA")
		)
	)
	(footprint ""
		(layer "F.Cu")
		(at 211.55152 -220.691456 -90)
		(property "Reference" "R2739"
			(at 0 0 270)
			(layer "F.SilkS")
			(hide yes)
			(effects
				(font
					(size 1.27 1.27)
				)
			)
		)
		(property "Value" ""
			(at 0 0 270)
			(layer "F.Fab")
			(effects
				(font
					(size 1.27 1.27)
				)
			)
		)
		(duplicate_pad_numbers_are_jumpers no)
		(fp_line
			(start -0.7874 0.4064)
			(end -0.7874 -0.4064)
			(stroke
				(width 0.1524)
				(type default)
			)
			(layer "F.SilkS")
		)
		(fp_line
			(start 0.7874 0.4064)
			(end -0.7874 0.4064)
			(stroke
				(width 0.1524)
				(type default)
			)
			(layer "F.SilkS")
		)
		(fp_line
			(start -0.7874 -0.4064)
			(end 0.7874 -0.4064)
			(stroke
				(width 0.1524)
				(type default)
			)
			(layer "F.SilkS")
		)
		(fp_line
			(start 0.7874 -0.4064)
			(end 0.7874 0.4064)
			(stroke
				(width 0.1524)
				(type default)
			)
			(layer "F.SilkS")
		)
		(fp_line
			(start -0.67945 0.3048)
			(end -0.67945 -0.305054)
			(stroke
				(width 0.1)
				(type default)
			)
			(layer "F.Fab")
		)
		(fp_line
			(start -0.12065 0.3048)
			(end -0.67945 0.3048)
			(stroke
				(width 0.1)
				(type default)
			)
			(layer "F.Fab")
		)
		(fp_line
			(start 0.120396 0.3048)
			(end 0.120396 0.2794)
			(stroke
				(width 0.1)
				(type default)
			)
			(layer "F.Fab")
		)
		(fp_line
			(start 0.67945 0.3048)
			(end 0.120396 0.3048)
			(stroke
				(width 0.1)
				(type default)
			)
			(layer "F.Fab")
		)
		(fp_line
			(start -0.12065 0.2794)
			(end -0.12065 0.3048)
			(stroke
				(width 0.1)
				(type default)
			)
			(layer "F.Fab")
		)
		(fp_line
			(start 0.120396 0.2794)
			(end -0.12065 0.2794)
			(stroke
				(width 0.1)
				(type default)
			)
			(layer "F.Fab")
		)
		(fp_line
			(start -0.12065 -0.2794)
			(end 0.12065 -0.2794)
			(stroke
				(width 0.1)
				(type default)
			)
			(layer "F.Fab")
		)
		(fp_line
			(start 0.12065 -0.2794)
			(end 0.12065 -0.3048)
			(stroke
				(width 0.1)
				(type default)
			)
			(layer "F.Fab")
		)
		(fp_line
			(start 0.12065 -0.3048)
			(end 0.67945 -0.3048)
			(stroke
				(width 0.1)
				(type default)
			)
			(layer "F.Fab")
		)
		(fp_line
			(start 0.67945 -0.3048)
			(end 0.67945 0.3048)
			(stroke
				(width 0.1)
				(type default)
			)
			(layer "F.Fab")
		)
		(fp_line
			(start -0.67945 -0.305054)
			(end -0.12065 -0.305054)
			(stroke
				(width 0.1)
				(type default)
			)
			(layer "F.Fab")
		)
		(fp_line
			(start -0.12065 -0.305054)
			(end -0.12065 -0.2794)
			(stroke
				(width 0.1)
				(type default)
			)
			(layer "F.Fab")
		)
		(pad "1" smd circle
			(at -0.40005 0 270)
			(size 0 0)
			(layers "F.Cu" "F.Mask" "F.Paste")
			(net "UART_MB_BIC_R_TX")
		)
		(pad "2" smd circle
			(at 0.40005 0 270)
			(size 0 0)
			(layers "F.Cu" "F.Mask" "F.Paste")
			(net "UART_MB_BIC_TX")
		)
	)
)
